(kicad_pcb
	(version 20260206)
	(generator "pcbnew")
	(generator_version "10.0")
	(general
		(thickness 1.6)
		(legacy_teardrops no)
	)
	(paper "A4")
	(title_block
		(title "Bryce Canyon_F.DPB_16315-1-OCP.brd")
		(comment 1 "Bryce Canyon / footprints 1405-1409 of 2223")
	)
	(layers
		(0 "F.Cu" signal "TOP")
		(4 "In1.Cu" signal "L2GND")
		(6 "In2.Cu" signal "L3")
		(8 "In3.Cu" signal "L4GND")
		(10 "In4.Cu" signal "L5")
		(12 "In5.Cu" signal "L6VCC")
		(14 "In6.Cu" signal "L7VCC")
		(16 "In7.Cu" signal "L8")
		(18 "In8.Cu" signal "L9GND")
		(20 "In9.Cu" signal "L10")
		(22 "In10.Cu" signal "L11GND")
		(2 "B.Cu" signal "BOTTOM")
		(9 "F.Adhes" user "F.Adhesive")
		(11 "B.Adhes" user "B.Adhesive")
		(13 "F.Paste" user "Package Geometry/Pastemask Top")
		(15 "B.Paste" user "Package Geometry/Pastemask Bottom")
		(5 "F.SilkS" user "Ref Des/Silkscreen Top")
		(7 "B.SilkS" user "Ref Des/Silkscreen Bottom")
		(1 "F.Mask" user "Board Geometry/Soldermask Top")
		(3 "B.Mask" user "Board Geometry/Soldermask Bottom")
		(17 "Dwgs.User" user "User.Drawings")
		(19 "Cmts.User" user "User.Comments")
		(21 "Eco1.User" user "User.Eco1")
		(23 "Eco2.User" user "User.Eco2")
		(25 "Edge.Cuts" user "Board Geometry/Outline")
		(27 "Margin" user)
		(31 "F.CrtYd" user "Package Geometry/Place Bound Top")
		(29 "B.CrtYd" user "Package Geometry/Place Bound Bottom")
		(35 "F.Fab" user "Ref Des/Assembly Top")
		(33 "B.Fab" user "Ref Des/Assembly Bottom")
	)
	(footprint ""
		(layer "F.Cu")
		(at 238.76 -388.4168)
		(property "Reference" "U26"
			(at 0 0 0)
			(layer "F.SilkS")
			(hide yes)
			(effects
				(font
					(size 1.27 1.27)
				)
			)
		)
		(property "Value" "ADM1278-2ACPZ-RL-1-GP"
			(at -4.7625 -7.4422 0)
			(unlocked yes)
			(layer "F.Fab")
			(hide yes)
			(effects
				(font
					(size 1.016 1.016)
					(thickness 0.1524)
				)
			)
		)
		(property "Device Type" "QFN32-G3D45-UH32"
			(at -4.7625 -8.9662 0)
			(unlocked yes)
			(layer "F.Fab")
			(hide yes)
			(effects
				(font
					(size 1.016 1.016)
					(thickness 0.1524)
				)
			)
		)
		(duplicate_pad_numbers_are_jumpers no)
		(fp_line
			(start -4.0513 -1.24968)
			(end -3.2893 -1.24968)
			(stroke
				(width 0.1524)
				(type default)
			)
			(layer "F.SilkS")
		)
		(fp_line
			(start -3.7973 1.24968)
			(end -3.2893 1.24968)
			(stroke
				(width 0.1524)
				(type default)
			)
			(layer "F.SilkS")
		)
		(fp_line
			(start -3.5179 -3.5179)
			(end -2.2479 -3.5179)
			(stroke
				(width 0.1524)
				(type default)
			)
			(layer "F.SilkS")
		)
		(fp_line
			(start -3.5179 -2.2479)
			(end -3.5179 -3.5179)
			(stroke
				(width 0.1524)
				(type default)
			)
			(layer "F.SilkS")
		)
		(fp_line
			(start -3.5179 2.2479)
			(end -3.5179 3.5179)
			(stroke
				(width 0.1524)
				(type default)
			)
			(layer "F.SilkS")
		)
		(fp_line
			(start -3.5179 3.5179)
			(end -2.2479 3.5179)
			(stroke
				(width 0.1524)
				(type default)
			)
			(layer "F.SilkS")
		)
		(fp_line
			(start -0.250698 -3.7973)
			(end -0.250698 -3.2893)
			(stroke
				(width 0.1524)
				(type default)
			)
			(layer "F.SilkS")
		)
		(fp_line
			(start -0.250698 4.0513)
			(end -0.250698 3.2893)
			(stroke
				(width 0.1524)
				(type default)
			)
			(layer "F.SilkS")
		)
		(fp_line
			(start 3.5179 2.2479)
			(end 3.5179 3.5179)
			(stroke
				(width 0.1524)
				(type default)
			)
			(layer "F.SilkS")
		)
		(fp_line
			(start 3.5179 3.5179)
			(end 2.2479 3.5179)
			(stroke
				(width 0.1524)
				(type default)
			)
			(layer "F.SilkS")
		)
		(fp_line
			(start 3.7973 1.749552)
			(end 3.2893 1.749552)
			(stroke
				(width 0.1524)
				(type default)
			)
			(layer "F.SilkS")
		)
		(fp_line
			(start 4.0513 -0.749808)
			(end 3.2893 -0.749808)
			(stroke
				(width 0.1524)
				(type default)
			)
			(layer "F.SilkS")
		)
		(fp_poly
			(pts
				(xy 2.2479 -3.5179) (xy 3.5179 -2.2479) (xy 3.5179 -3.5179)
			)
			(stroke
				(width 0)
				(type default)
			)
			(fill yes)
			(layer "F.SilkS")
		)
		(fp_rect
			(start -2.5019 2.5019)
			(end 2.5019 -2.5019)
			(stroke
				(width 0)
				(type default)
			)
			(fill no)
			(layer "F.CrtYd")
		)
		(fp_poly
			(pts
				(xy -3.5179 3.5179) (xy -3.5179 -3.5179) (xy 3.5179 -3.5179) (xy 3.5179 3.5179) (xy -2.49682 3.5179)
				(xy -2.49682 2.5019) (xy 2.5019 2.5019) (xy 2.5019 -2.5019) (xy -2.5019 -2.5019) (xy -2.5019 3.5179)
			)
			(stroke
				(width 0)
				(type default)
			)
			(fill no)
			(layer "F.CrtYd")
		)
		(fp_rect
			(start -3.5179 3.5179)
			(end 3.5179 -3.5179)
			(stroke
				(width 0)
				(type default)
			)
			(fill no)
			(layer "F.Fab")
		)
		(pad "1" smd rect
			(at 1.75006 -2.5527)
			(size 0.3048 0.9144)
			(layers "F.Cu" "F.Mask" "F.Paste")
			(net "MB3_PSET_R")
		)
		(pad "2" smd rect
			(at 1.249934 -2.4765)
			(size 0.3048 1.0668)
			(layers "F.Cu" "F.Mask" "F.Paste")
			(net "MB3_VCAP_R")
		)
		(pad "3" smd rect
			(at 0.750062 -2.4765)
			(size 0.3048 1.0668)
			(layers "F.Cu" "F.Mask" "F.Paste")
			(net "MB3_ISET_R")
		)
		(pad "4" smd rect
			(at 0.249936 -2.4765)
			(size 0.3048 1.0668)
			(layers "F.Cu" "F.Mask" "F.Paste")
			(net "MB3_ISTART_R")
		)
		(pad "5" smd rect
			(at -0.249936 -2.4765)
			(size 0.3048 1.0668)
			(layers "F.Cu" "F.Mask" "F.Paste")
			(net "MB3_TIME_R")
		)
		(pad "6" smd rect
			(at -0.750062 -2.4765)
			(size 0.3048 1.0668)
			(layers "F.Cu" "F.Mask" "F.Paste")
			(net "Net_1348")
		)
		(pad "7" smd rect
			(at -1.249934 -2.4765)
			(size 0.3048 1.0668)
			(layers "F.Cu" "F.Mask" "F.Paste")
			(net "MB3_CM_ADR1_R")
		)
		(pad "8" smd rect
			(at -1.75006 -2.5527)
			(size 0.3048 0.9144)
			(layers "F.Cu" "F.Mask" "F.Paste")
			(net "MB3_CM_ADR2_R")
		)
		(pad "9" smd rect
			(at -2.5527 -1.75006)
			(size 0.9144 0.3048)
			(layers "F.Cu" "F.Mask" "F.Paste")
			(net "MB3_SPISS_PD")
		)
		(pad "10" smd rect
			(at -2.4765 -1.249934)
			(size 1.0668 0.3048)
			(layers "F.Cu" "F.Mask" "F.Paste")
			(net "Net_1352")
		)
		(pad "11" smd rect
			(at -2.4765 -0.750062)
			(size 1.0668 0.3048)
			(layers "F.Cu" "F.Mask" "F.Paste")
			(net "Net_1351")
		)
		(pad "12" smd rect
			(at -2.4765 -0.249936)
			(size 1.0668 0.3048)
			(layers "F.Cu" "F.Mask" "F.Paste")
			(net "MB3_HS_ENABLE")
		)
		(pad "13" smd rect
			(at -2.4765 0.249936)
			(size 1.0668 0.3048)
			(layers "F.Cu" "F.Mask" "F.Paste")
			(net "Net_1350")
		)
		(pad "14" smd rect
			(at -2.4765 0.750062)
			(size 1.0668 0.3048)
			(layers "F.Cu" "F.Mask" "F.Paste")
			(net "Net_1349")
		)
		(pad "15" smd rect
			(at -2.4765 1.249934)
			(size 1.0668 0.3048)
			(layers "F.Cu" "F.Mask" "F.Paste")
			(net "MB3_SDA_R")
		)
		(pad "16" smd rect
			(at -2.5527 1.75006)
			(size 0.9144 0.3048)
			(layers "F.Cu" "F.Mask" "F.Paste")
			(net "MB3_SCL_R")
		)
		(pad "17" smd rect
			(at -1.75006 2.5527)
			(size 0.3048 0.9144)
			(layers "F.Cu" "F.Mask" "F.Paste")
			(net "MB3_RETRY_R")
		)
		(pad "18" smd rect
			(at -1.249934 2.4765)
			(size 0.3048 1.0668)
			(layers "F.Cu" "F.Mask" "F.Paste")
			(net "P12V_A_PGOOD")
		)
		(pad "19" smd rect
			(at -0.750062 2.4765)
			(size 0.3048 1.0668)
			(layers "F.Cu" "F.Mask" "F.Paste")
			(net "Net_1353")
		)
		(pad "20" smd rect
			(at -0.249936 2.4765)
			(size 0.3048 1.0668)
			(layers "F.Cu" "F.Mask" "F.Paste")
			(net "MB3_CM_VOUT_R")
		)
		(pad "21" smd rect
			(at 0.249936 2.4765)
			(size 0.3048 1.0668)
			(layers "F.Cu" "F.Mask" "F.Paste")
			(net "MB3_P12V_PWGIN_R")
		)
		(pad "22" smd rect
			(at 0.750062 2.4765)
			(size 0.3048 1.0668)
			(layers "F.Cu" "F.Mask" "F.Paste")
			(net "AGND_CURRENT_DPB")
		)
		(pad "23" smd rect
			(at 1.249934 2.4765)
			(size 0.3048 1.0668)
			(layers "F.Cu" "F.Mask" "F.Paste")
			(net "GND")
		)
		(pad "24" smd rect
			(at 1.75006 2.5527)
			(size 0.3048 0.9144)
			(layers "F.Cu" "F.Mask" "F.Paste")
			(net "MB3_CM_GATE")
		)
		(pad "25" smd rect
			(at 2.5527 1.75006)
			(size 0.9144 0.3048)
			(layers "F.Cu" "F.Mask" "F.Paste")
			(net "MB3_TEMP")
		)
		(pad "26" smd rect
			(at 2.4765 1.249934)
			(size 1.0668 0.3048)
			(layers "F.Cu" "F.Mask" "F.Paste")
			(net "MB3_CM_SENSE_N")
		)
		(pad "27" smd rect
			(at 2.4765 0.750062)
			(size 1.0668 0.3048)
			(layers "F.Cu" "F.Mask" "F.Paste")
			(net "MB3_HS_SENSE_N")
		)
		(pad "28" smd rect
			(at 2.4765 0.249936)
			(size 1.0668 0.3048)
			(layers "F.Cu" "F.Mask" "F.Paste")
			(net "MB3_HS_SENSE_P")
		)
		(pad "29" smd rect
			(at 2.4765 -0.249936)
			(size 1.0668 0.3048)
			(layers "F.Cu" "F.Mask" "F.Paste")
			(net "MB3_CM_SENSE_P")
		)
		(pad "30" smd rect
			(at 2.4765 -0.750062)
			(size 1.0668 0.3048)
			(layers "F.Cu" "F.Mask" "F.Paste")
			(net "MB3_P12V_HS")
		)
		(pad "31" smd rect
			(at 2.4765 -1.249934)
			(size 1.0668 0.3048)
			(layers "F.Cu" "F.Mask" "F.Paste")
			(net "MB3_CM_UV_R")
		)
		(pad "32" smd rect
			(at 2.5527 -1.75006)
			(size 0.9144 0.3048)
			(layers "F.Cu" "F.Mask" "F.Paste")
			(net "MB3_CM_OV_R")
		)
		(pad "33" smd rect
			(at 0 0)
			(size 3.4544 3.4544)
			(layers "F.Cu" "F.Mask" "F.Paste")
			(net "AGND_CURRENT_DPB")
		)
	)
	(footprint ""
		(layer "F.Cu")
		(at 77.942948 -53.482494 -90)
		(property "Reference" "R743"
			(at 0 0 270)
			(layer "F.SilkS")
			(hide yes)
			(effects
				(font
					(size 1.27 1.27)
				)
			)
		)
		(property "Value" "300KR2F-GP"
			(at 0.064008 -3.993896 270)
			(unlocked yes)
			(layer "F.Fab")
			(hide yes)
			(effects
				(font
					(size 1.016 1.016)
					(thickness 0.1524)
				)
			)
		)
		(property "Device Type" "R402H16"
			(at 0.064008 -5.517896 270)
			(unlocked yes)
			(layer "F.Fab")
			(hide yes)
			(effects
				(font
					(size 1.016 1.016)
					(thickness 0.1524)
				)
			)
		)
		(duplicate_pad_numbers_are_jumpers no)
		(fp_line
			(start -0.508 -0.9398)
			(end -0.508 0.9398)
			(stroke
				(width 0.1524)
				(type default)
			)
			(layer "F.SilkS")
		)
		(fp_line
			(start 0.508 -0.9398)
			(end -0.508 -0.9398)
			(stroke
				(width 0.1524)
				(type default)
			)
			(layer "F.SilkS")
		)
		(fp_rect
			(start -0.508 0.9398)
			(end 0.508 -0.9398)
			(stroke
				(width 0)
				(type default)
			)
			(fill no)
			(layer "F.CrtYd")
		)
		(fp_rect
			(start -0.508 0.9398)
			(end 0.508 -0.9398)
			(stroke
				(width 0)
				(type default)
			)
			(fill no)
			(layer "F.Fab")
		)
		(pad "1" smd custom
			(at 0 -0.4445 270)
			(size 0.1397 0.1397)
			(layers "F.Cu" "F.Mask" "F.Paste")
			(net "SW_HDD_N26")
			(options
				(clearance outline)
				(anchor circle)
			)
			(primitives
				(gr_poly
					(pts
						(arc
							(start -0.1778 -0.2794)
							(mid -0.249642 -0.249642)
							(end -0.2794 -0.1778)
						)
						(arc
							(start -0.2794 0.1778)
							(mid -0.249642 0.249642)
							(end -0.1778 0.2794)
						)
						(arc
							(start 0.1778 0.2794)
							(mid 0.249642 0.249642)
							(end 0.2794 0.1778)
						)
						(arc
							(start 0.2794 -0.1778)
							(mid 0.249642 -0.249642)
							(end 0.1778 -0.2794)
						)
					)
					(width 0)
					(fill yes)
				)
			)
		)
		(pad "2" smd custom
			(at 0 0.4445 270)
			(size 0.1397 0.1397)
			(layers "F.Cu" "F.Mask" "F.Paste")
			(net "P12V_A")
			(options
				(clearance outline)
				(anchor circle)
			)
			(primitives
				(gr_poly
					(pts
						(arc
							(start -0.1778 -0.2794)
							(mid -0.249642 -0.249642)
							(end -0.2794 -0.1778)
						)
						(arc
							(start -0.2794 0.1778)
							(mid -0.249642 0.249642)
							(end -0.1778 0.2794)
						)
						(arc
							(start 0.1778 0.2794)
							(mid 0.249642 0.249642)
							(end 0.2794 0.1778)
						)
						(arc
							(start 0.2794 -0.1778)
							(mid 0.249642 -0.249642)
							(end 0.1778 -0.2794)
						)
					)
					(width 0)
					(fill yes)
				)
			)
		)
	)
	(footprint ""
		(layer "F.Cu")
		(at 364.0328 -143.4084)
		(property "Reference" "C555"
			(at 0 0 0)
			(layer "F.SilkS")
			(hide yes)
			(effects
				(font
					(size 1.27 1.27)
				)
			)
		)
		(property "Value" "SC1KP50V2KX-1GP"
			(at 1.1811 -2.7051 0)
			(unlocked yes)
			(layer "F.Fab")
			(hide yes)
			(effects
				(font
					(size 1.016 1.016)
					(thickness 0.1524)
				)
			)
		)
		(property "Device Type" "C402H22"
			(at 1.1811 -4.2291 0)
			(unlocked yes)
			(layer "F.Fab")
			(hide yes)
			(effects
				(font
					(size 1.016 1.016)
					(thickness 0.1524)
				)
			)
		)
		(duplicate_pad_numbers_are_jumpers no)
		(fp_rect
			(start -0.4318 0.9525)
			(end 0.4318 -0.9525)
			(stroke
				(width 0)
				(type default)
			)
			(fill no)
			(layer "F.CrtYd")
		)
		(fp_rect
			(start -0.4318 0.9525)
			(end 0.4318 -0.9525)
			(stroke
				(width 0)
				(type default)
			)
			(fill no)
			(layer "F.Fab")
		)
		(pad "1" smd custom
			(at 0 -0.4445)
			(size 0.1524 0.1524)
			(layers "F.Cu" "F.Mask" "F.Paste")
			(net "MB1_TEMP_B")
			(options
				(clearance outline)
				(anchor circle)
			)
			(primitives
				(gr_poly
					(pts
						(arc
							(start 0.3048 -0.2032)
							(mid 0.275042 -0.275042)
							(end 0.2032 -0.3048)
						)
						(arc
							(start -0.2032 -0.3048)
							(mid -0.275042 -0.275042)
							(end -0.3048 -0.2032)
						)
						(arc
							(start -0.3048 0.2032)
							(mid -0.275042 0.275042)
							(end -0.2032 0.3048)
						)
						(arc
							(start 0.2032 0.3048)
							(mid 0.275042 0.275042)
							(end 0.3048 0.2032)
						)
					)
					(width 0)
					(fill yes)
				)
			)
		)
		(pad "2" smd custom
			(at 0 0.4445)
			(size 0.1524 0.1524)
			(layers "F.Cu" "F.Mask" "F.Paste")
			(net "MB1_TEMP_E")
			(options
				(clearance outline)
				(anchor circle)
			)
			(primitives
				(gr_poly
					(pts
						(arc
							(start 0.3048 -0.2032)
							(mid 0.275042 -0.275042)
							(end 0.2032 -0.3048)
						)
						(arc
							(start -0.2032 -0.3048)
							(mid -0.275042 -0.275042)
							(end -0.3048 -0.2032)
						)
						(arc
							(start -0.3048 0.2032)
							(mid -0.275042 0.275042)
							(end -0.2032 0.3048)
						)
						(arc
							(start 0.2032 0.3048)
							(mid 0.275042 0.275042)
							(end 0.3048 0.2032)
						)
					)
					(width 0)
					(fill yes)
				)
			)
		)
	)
	(footprint ""
		(layer "F.Cu")
		(at 374.892062 -294.392858 180)
		(property "Reference" "R297"
			(at 0 0 180)
			(layer "F.SilkS")
			(hide yes)
			(effects
				(font
					(size 1.27 1.27)
				)
			)
		)
		(property "Value" "130R3F-GP"
			(at -0.0254 -2.5146 180)
			(unlocked yes)
			(layer "F.Fab")
			(hide yes)
			(effects
				(font
					(size 1.016 1.016)
					(thickness 0.1524)
				)
			)
		)
		(property "Device Type" "R603H22"
			(at -0.0254 -4.0386 180)
			(unlocked yes)
			(layer "F.Fab")
			(hide yes)
			(effects
				(font
					(size 1.016 1.016)
					(thickness 0.1524)
				)
			)
		)
		(duplicate_pad_numbers_are_jumpers no)
		(fp_line
			(start 0.2032 0)
			(end 0.4826 0)
			(stroke
				(width 0.2032)
				(type default)
			)
			(layer "F.SilkS")
		)
		(fp_line
			(start -0.4826 0)
			(end -0.2032 0)
			(stroke
				(width 0.2032)
				(type default)
			)
			(layer "F.SilkS")
		)
		(fp_rect
			(start -0.5842 1.3335)
			(end 0.5842 -1.3335)
			(stroke
				(width 0)
				(type default)
			)
			(fill no)
			(layer "F.CrtYd")
		)
		(fp_rect
			(start -0.5842 1.3335)
			(end 0.5842 -1.3335)
			(stroke
				(width 0)
				(type default)
			)
			(fill no)
			(layer "F.Fab")
		)
		(pad "1" smd custom
			(at 0 -0.762 180)
			(size 0.2159 0.2159)
			(layers "F.Cu" "F.Mask" "F.Paste")
			(net "P5V_B")
			(options
				(clearance outline)
				(anchor circle)
			)
			(primitives
				(gr_poly
					(pts
						(arc
							(start -0.3302 -0.4318)
							(mid -0.402042 -0.402042)
							(end -0.4318 -0.3302)
						)
						(arc
							(start -0.4318 0.3302)
							(mid -0.402042 0.402042)
							(end -0.3302 0.4318)
						)
						(arc
							(start 0.3302 0.4318)
							(mid 0.402042 0.402042)
							(end 0.4318 0.3302)
						)
						(arc
							(start 0.4318 -0.3302)
							(mid 0.402042 -0.402042)
							(end 0.3302 -0.4318)
						)
					)
					(width 0)
					(fill yes)
				)
			)
		)
		(pad "2" smd custom
			(at 0 0.762 180)
			(size 0.2159 0.2159)
			(layers "F.Cu" "F.Mask" "F.Paste")
			(net "FLT_HDD32")
			(options
				(clearance outline)
				(anchor circle)
			)
			(primitives
				(gr_poly
					(pts
						(arc
							(start -0.3302 -0.4318)
							(mid -0.402042 -0.402042)
							(end -0.4318 -0.3302)
						)
						(arc
							(start -0.4318 0.3302)
							(mid -0.402042 0.402042)
							(end -0.3302 0.4318)
						)
						(arc
							(start 0.3302 0.4318)
							(mid 0.402042 0.402042)
							(end 0.4318 0.3302)
						)
						(arc
							(start 0.4318 -0.3302)
							(mid 0.402042 -0.402042)
							(end 0.3302 -0.4318)
						)
					)
					(width 0)
					(fill yes)
				)
			)
		)
	)
	(footprint ""
		(layer "F.Cu")
		(at 109.492796 -169.523918 90)
		(property "Reference" "C244"
			(at 0 0 90)
			(layer "F.SilkS")
			(hide yes)
			(effects
				(font
					(size 1.27 1.27)
				)
			)
		)
		(property "Value" "SCD033U25V2KX-GP"
			(at 1.1811 -2.7051 90)
			(unlocked yes)
			(layer "F.Fab")
			(hide yes)
			(effects
				(font
					(size 1.016 1.016)
					(thickness 0.1524)
				)
			)
		)
		(property "Device Type" "C402H22"
			(at 1.1811 -4.2291 90)
			(unlocked yes)
			(layer "F.Fab")
			(hide yes)
			(effects
				(font
					(size 1.016 1.016)
					(thickness 0.1524)
				)
			)
		)
		(duplicate_pad_numbers_are_jumpers no)
		(fp_rect
			(start -0.4318 0.9525)
			(end 0.4318 -0.9525)
			(stroke
				(width 0)
				(type default)
			)
			(fill no)
			(layer "F.CrtYd")
		)
		(fp_rect
			(start -0.4318 0.9525)
			(end 0.4318 -0.9525)
			(stroke
				(width 0)
				(type default)
			)
			(fill no)
			(layer "F.Fab")
		)
		(pad "1" smd custom
			(at 0 -0.4445 90)
			(size 0.1524 0.1524)
			(layers "F.Cu" "F.Mask" "F.Paste")
			(net "P12V_A")
			(options
				(clearance outline)
				(anchor circle)
			)
			(primitives
				(gr_poly
					(pts
						(arc
							(start 0.3048 -0.2032)
							(mid 0.275042 -0.275042)
							(end 0.2032 -0.3048)
						)
						(arc
							(start -0.2032 -0.3048)
							(mid -0.275042 -0.275042)
							(end -0.3048 -0.2032)
						)
						(arc
							(start -0.3048 0.2032)
							(mid -0.275042 0.275042)
							(end -0.2032 0.3048)
						)
						(arc
							(start 0.2032 0.3048)
							(mid 0.275042 0.275042)
							(end 0.3048 0.2032)
						)
					)
					(width 0)
					(fill yes)
				)
			)
		)
		(pad "2" smd custom
			(at 0 0.4445 90)
			(size 0.1524 0.1524)
			(layers "F.Cu" "F.Mask" "F.Paste")
			(net "SW_HDD_N15")
			(options
				(clearance outline)
				(anchor circle)
			)
			(primitives
				(gr_poly
					(pts
						(arc
							(start 0.3048 -0.2032)
							(mid 0.275042 -0.275042)
							(end 0.2032 -0.3048)
						)
						(arc
							(start -0.2032 -0.3048)
							(mid -0.275042 -0.275042)
							(end -0.3048 -0.2032)
						)
						(arc
							(start -0.3048 0.2032)
							(mid -0.275042 0.275042)
							(end -0.2032 0.3048)
						)
						(arc
							(start 0.2032 0.3048)
							(mid 0.275042 0.275042)
							(end 0.3048 0.2032)
						)
					)
					(width 0)
					(fill yes)
				)
			)
		)
	)
)
